%FSTAX25Y25*%
%MOIN*%
%SFA1B1*%

%IPPOS*%
%ADD18C,0.005000*%
%ADD112C,0.008000*%
%ADD113C,0.020000*%
%ADD120C,0.075000*%
%ADD126C,0.016000*%
%ADD130C,0.025000*%
%LNtimecard-dc-beta-v1-1*%
%LPD*%
G36*
X0226378Y0391732D02*
X0672244D01*
Y0310039*
X0658465*
Y0366142*
X0226378*
Y0344488*
X0054134*
Y0433071*
X0226378*
Y0391732*
G37*
G36*
X0376969Y019685D02*
X033563D01*
Y0212598*
X0376969*
Y019685*
G37*
G36*
X0599213Y0140551D02*
X0594095D01*
Y014685*
X0599213*
Y0140551*
G37*
%LNtimecard-dc-beta-v1-2*%
%LPC*%
G36*
X016715Y041271D02*
X0166071D01*
X0165028Y041243*
X0164093Y041189*
X016333Y0411127*
X016279Y0410192*
X0162617Y0409546*
X0162533Y0409232*
X0162033Y0409298*
Y0409767*
X016179Y0410355*
X0161339Y0410805*
X0160751Y0411049*
X0160115*
X0159527Y0410805*
X0159077Y0410355*
X0158833Y0409767*
Y0409131*
X0159077Y0408542*
X0159527Y0408092*
X0160115Y0407849*
X0160751*
X0161339Y0408092*
X016179Y0408542*
X0162033Y040913*
X0162511Y0409077*
Y0408748*
Y0408071*
X016279Y0407028*
X016333Y0406093*
X0164093Y040533*
X0165028Y040479*
X0166071Y0404511*
X016715*
X0168193Y040479*
X0169127Y040533*
X016989Y0406093*
X017043Y0407028*
X0170709Y0408071*
Y040915*
X017043Y0410192*
X016989Y0411127*
X0169127Y041189*
X0168193Y041243*
X016715Y041271*
G37*
G36*
X019715D02*
X0196071D01*
X0195028Y041243*
X0194093Y041189*
X019333Y0411127*
X019279Y0410192*
X0192511Y040915*
Y0408071*
X019279Y0407028*
X019333Y0406093*
X0194093Y040533*
X0195028Y040479*
X0196071Y0404511*
X019715*
X0198193Y040479*
X0199127Y040533*
X019989Y0406093*
X020043Y0407028*
X0200709Y0408071*
Y0408857*
X020071Y0408902*
X0201209Y0409001*
X0201239Y040893*
X0201399Y0408542*
X020185Y0408092*
X0202438Y0407849*
X0203074*
X0203662Y0408092*
X0204112Y0408542*
X0204356Y0409131*
Y0409767*
X0204112Y0410355*
X0203662Y0410805*
X0203074Y0411049*
X0202438*
X020185Y0410805*
X0201399Y0410355*
X0201156Y0409767*
Y0409483*
Y0409416*
X0200656Y040935*
X0200643Y0409398*
X020043Y0410192*
X019989Y0411127*
X0199127Y041189*
X0198193Y041243*
X019715Y041271*
G37*
G36*
X0124715Y0403194D02*
X0124079D01*
X0123491Y040295*
X012304Y04025*
X0122797Y0401912*
Y0401275*
X012304Y0400687*
X0123491Y0400237*
X0124079Y0399994*
X0124715*
X0125303Y0400237*
X0125753Y0400687*
X0125997Y0401275*
Y0401912*
X0125753Y04025*
X0125303Y040295*
X0124715Y0403194*
G37*
G36*
X0104548Y040306D02*
X0103912D01*
X0103324Y0402817*
X0102874Y0402367*
X010263Y0401779*
Y0401142*
X0102874Y0400554*
X0103324Y0400104*
X0103912Y039986*
X0104548*
X0105137Y0400104*
X0105587Y0400554*
X010583Y0401142*
Y0401779*
X0105587Y0402367*
X0105137Y0402817*
X0104548Y040306*
G37*
G36*
X0084382Y0402927D02*
X0083745D01*
X0083157Y0402683*
X0082707Y0402233*
X0082464Y0401645*
Y0401009*
X0082707Y0400421*
X0083157Y0399971*
X0083745Y0399727*
X0084382*
X008497Y0399971*
X008542Y0400421*
X0085663Y0401009*
Y0401645*
X008542Y0402233*
X008497Y0402683*
X0084382Y0402927*
G37*
G36*
X0064215Y0402894D02*
X0063579D01*
X006299Y040265*
X006254Y04022*
X0062297Y0401612*
Y0400975*
X006254Y0400387*
X006299Y0399937*
X0063579Y0399694*
X0064215*
X0064803Y0399937*
X0065253Y0400387*
X0065497Y0400975*
Y0401612*
X0065253Y04022*
X0064803Y040265*
X0064215Y0402894*
G37*
G36*
X0217806Y0359295D02*
X021717D01*
X0216582Y0359051*
X0216132Y0358601*
X0215888Y0358013*
Y0357377*
X0216132Y0356789*
X0216582Y0356339*
X021717Y0356095*
X0217806*
X0218394Y0356339*
X0218845Y0356789*
X0219088Y0357377*
Y0358013*
X0218845Y0358601*
X0218394Y0359051*
X0217806Y0359295*
G37*
G36*
X0182046Y035908D02*
X0181409D01*
X0180821Y0358837*
X0180371Y0358387*
X0180127Y0357799*
Y0357162*
X0180371Y0356574*
X0180821Y0356124*
X0181409Y035588*
X0182046*
X0182634Y0356124*
X0183084Y0356574*
X0183327Y0357162*
Y0357799*
X0183084Y0358387*
X0182634Y0358837*
X0182046Y035908*
G37*
G36*
X0164275D02*
X0163638D01*
X016305Y0358837*
X01626Y0358387*
X0162357Y0357799*
Y0357162*
X01626Y0356574*
X016305Y0356124*
X0163638Y035588*
X0164275*
X0164863Y0356124*
X0165313Y0356574*
X0165557Y0357162*
Y0357799*
X0165313Y0358387*
X0164863Y0358837*
X0164275Y035908*
G37*
G36*
X0200121Y0358884D02*
X0199485D01*
X0198897Y035864*
X0198447Y035819*
X0198203Y0357602*
Y0356965*
X0198447Y0356377*
X0198897Y0355927*
X0199485Y0355683*
X0200121*
X020071Y0355927*
X020116Y0356377*
X0201403Y0356965*
Y0357602*
X020116Y035819*
X020071Y035864*
X0200121Y0358884*
G37*
G36*
X035751Y0211589D02*
X0356761D01*
X0356069Y0211302*
X0355539Y0210772*
X0355253Y021008*
Y0209331*
X0355539Y0208639*
X0356069Y0208109*
X0356761Y0207822*
X035751*
X0358202Y0208109*
X0358732Y0208639*
X0359018Y0209331*
Y021008*
X0358732Y0210772*
X0358202Y0211302*
X035751Y0211589*
G37*
G36*
X0360555Y0202387D02*
X0359918D01*
X035933Y0202144*
X035888Y0201694*
X0358636Y0201106*
Y0200469*
X035888Y0199881*
X035933Y0199431*
X0359918Y0199187*
X0360555*
X0361142Y0199431*
X0361593Y0199881*
X0361836Y0200469*
Y0201106*
X0361593Y0201694*
X0361142Y0202144*
X0360555Y0202387*
G37*
G36*
X0354649D02*
X0354012D01*
X0353424Y0202144*
X0352974Y0201694*
X0352731Y0201106*
Y0200469*
X0352974Y0199881*
X0353424Y0199431*
X0354012Y0199187*
X0354649*
X0355237Y0199431*
X0355687Y0199881*
X0355931Y0200469*
Y0201106*
X0355687Y0201694*
X0355237Y0202144*
X0354649Y0202387*
G37*
%LNtimecard-dc-beta-v1-3*%
%LPD*%
G54D18*
X026067Y0077514D02*
D01*
X0260663Y0077711*
X0260642Y0077907*
X0260608Y0078101*
X026056Y0078293*
X0260499Y007848*
X0260425Y0078663*
X0260339Y0078841*
X026024Y0079012*
X026013Y0079175*
X0260008Y0079331*
X0259876Y0079477*
X0259842Y0079513*
X0257742Y0039631D02*
D01*
X0258218Y0040141*
X0258657Y0040683*
X0259057Y0041255*
X0259417Y0041853*
X0259733Y0042475*
X0260006Y0043118*
X0260233Y0043778*
X0260414Y0044452*
X0260547Y0045137*
X0260632Y004583*
X0260669Y0046527*
X026067Y0046702*
X0238816Y0040485D02*
D01*
X0238831Y0040485*
X0238847Y0040487*
X0238863Y0040489*
X0238878Y0040493*
X0238893Y0040498*
X0238908Y0040504*
X0238922Y0040511*
X0238936Y0040519*
X0238949Y0040528*
X0238961Y0040538*
X0238973Y0040548*
X0238976Y0040551*
X0238058Y0040485D02*
D01*
X0238023Y0040483*
X0237988Y004048*
X0237954Y0040474*
X023792Y0040465*
X0237886Y0040454*
X0237854Y0040441*
X0237823Y0040426*
X0237793Y0040409*
X0237764Y0040389*
X0237736Y0040368*
X023771Y0040344*
X0237704Y0040338*
D01*
X023768Y0040312*
X0237658Y0040285*
X0237638Y0040256*
X023762Y0040227*
X0237604Y0040195*
X023759Y0040163*
X0237579Y004013*
X023757Y0040097*
X0237563Y0040063*
X0237559Y0040028*
X0237557Y0039993*
X0237558Y0039985*
D01*
X0237559Y003995*
X0237562Y0039915*
X0237568Y0039881*
X0237577Y0039847*
X0237588Y0039813*
X0237601Y0039781*
X0237616Y003975*
X0237633Y003972*
X0237653Y0039691*
X0237674Y0039663*
X0237698Y0039637*
X0237704Y0039631*
X0262598Y0079513D02*
D01*
X0262463Y0079368*
X0262339Y0079215*
X0262226Y0079053*
X0262124Y0078884*
X0262034Y0078708*
X0261957Y0078527*
X0261893Y007834*
X0261842Y0078149*
X0261804Y0077956*
X026178Y007776*
X026177Y0077563*
X0261771Y0077514*
X0258523Y0038857D02*
D01*
X025905Y0039422*
X0259537Y0040024*
X0259981Y0040658*
X026038Y0041321*
X0260731Y0042011*
X0261034Y0042723*
X0261285Y0043455*
X0261486Y0044202*
X0261633Y0044962*
X0261728Y004573*
X0261768Y0046503*
X0261771Y0046697*
X0253548Y0034333D02*
D01*
X0253623Y0034335*
X0253699Y0034343*
X0253774Y0034356*
X0253847Y0034375*
X025392Y0034398*
X025399Y0034427*
X0254058Y003446*
X0254124Y0034498*
X0254187Y003454*
X0254247Y0034587*
X0254303Y0034638*
X0254318Y0034652*
X0236458Y0039985D02*
D01*
X0236456Y0040019*
X0236453Y0040054*
X0236447Y0040088*
X0236438Y0040122*
X0236427Y0040156*
X0236414Y0040188*
X0236399Y0040219*
X0236382Y0040249*
X0236362Y0040278*
X0236341Y0040306*
X0236317Y0040332*
X0236311Y0040338*
D01*
X0236285Y0040361*
X0236258Y0040383*
X0236229Y0040403*
X0236199Y0040421*
X0236168Y0040437*
X0236136Y0040451*
X0236103Y0040462*
X0236069Y0040471*
X0236035Y0040478*
X0236Y0040482*
X0235965Y0040484*
X0235958Y0040485*
X0236458Y0039757D02*
D01*
X023646Y0039683*
X0236468Y003961*
X023648Y0039538*
X0236498Y0039467*
X0236521Y0039397*
X0236548Y0039329*
X023658Y0039264*
X0236617Y00392*
X0236658Y0039139*
X0236703Y0039082*
X0236752Y0039027*
X0236765Y0039015*
X0235039Y0040551D02*
D01*
X023505Y004054*
X0235062Y004053*
X0235075Y0040521*
X0235089Y0040513*
X0235103Y0040505*
X0235117Y0040499*
X0235132Y0040494*
X0235148Y004049*
X0235163Y0040487*
X0235179Y0040485*
X0235195Y0040484*
X02352Y0040485*
X0238963Y0036816D02*
D01*
X0239395Y0036412*
X0239855Y0036039*
X024034Y00357*
X0240847Y0035395*
X0241375Y0035126*
X024192Y0034895*
X0242479Y0034702*
X0243051Y0034549*
X0243632Y0034436*
X0244219Y0034364*
X0244811Y0034333*
X0244959Y0034333*
X0270722Y0097479D02*
D01*
X027061Y0097359*
X0270508Y0097233*
X0270414Y0097099*
X027033Y0096959*
X0270256Y0096814*
X0270193Y0096664*
X027014Y009651*
X0270097Y0096353*
X0270066Y0096193*
X0270047Y0096031*
X0270038Y0095868*
X0270038Y0095828*
X0247417Y0072239D02*
D01*
X024694Y0071728*
X0246501Y0071186*
X0246101Y0070614*
X0245741Y0070016*
X0245425Y0069394*
X0245152Y0068751*
X0244925Y0068091*
X0244744Y0067417*
X0244611Y0066732*
X0244526Y0066039*
X0244489Y0065342*
X0244488Y0065168*
X0245315Y0041421D02*
D01*
X0245314Y0041421*
X0245313Y0041421*
X0245313Y0041422*
X0245312Y0041422*
X0245312Y0041423*
X0245317Y0041419D02*
D01*
X0245411Y0041344*
X024551Y0041276*
X0245614Y0041215*
X0245721Y0041161*
X0245832Y0041115*
X0245946Y0041077*
X0246063Y0041047*
X0246181Y0041025*
X0246301Y0041012*
X0246421Y0041007*
X0246541Y004101*
X0246661Y0041021*
X0246779Y0041041*
X0246896Y004107*
X0246964Y004109*
X0244488Y0042376D02*
D01*
X0244488Y0042338*
X0244492Y0042301*
X0244498Y0042265*
X0244507Y0042229*
X0244518Y0042193*
X0244531Y0042159*
X0244547Y0042125*
X0244566Y0042093*
X0244586Y0042062*
X0244609Y0042032*
X0244633Y0042005*
X024466Y0041978*
X0244679Y0041963*
D01*
X0244679Y0041962*
X0244679Y0041962*
X0244679Y0041962*
X0244679Y0041962*
X024468Y0041962*
Y0041962*
X0268938Y0096056D02*
D01*
X0268933Y009618*
X026892Y0096304*
X0268898Y0096427*
X0268868Y0096548*
X026883Y0096666*
X0268783Y0096782*
X0268729Y0096894*
X0268666Y0097001*
X0268597Y0097105*
X026852Y0097203*
X0268437Y0097295*
X0268415Y0097318*
Y0094793D02*
D01*
X0268499Y0094884*
X0268578Y009498*
X0268649Y0095082*
X0268713Y0095189*
X026877Y00953*
X0268819Y0095415*
X0268859Y0095533*
X0268891Y0095653*
X0268915Y0095775*
X026893Y0095899*
X0268937Y0096023*
X0268938Y0096056*
X0246635Y0073013D02*
D01*
X0245966Y0072295*
X0245348Y0071533*
X0244786Y007073*
X0244281Y0069889*
X0243835Y0069015*
X0243452Y0068112*
X0243133Y0067185*
X0242879Y0066237*
X0242692Y0065275*
X0242572Y0064301*
X0242521Y0063322*
X024252Y006308*
X0249651Y0039021D02*
D01*
X0249757Y0039024*
X0249863Y0039035*
X0249969Y0039054*
X0250072Y003908*
X0250174Y0039113*
X0250273Y0039153*
X0250369Y00392*
X0250461Y0039253*
X025055Y0039313*
X0250634Y0039378*
X0250713Y003945*
X0250788Y0039527*
X0250856Y0039609*
X0250919Y0039695*
X0250976Y0039786*
X0251026Y003988*
X0251069Y0039977*
X0251106Y0040078*
X0251135Y004018*
X0251157Y0040285*
X0251172Y0040391*
X025118Y0040497*
X0251181Y0040551*
X0275984Y0079513D02*
D01*
X0275849Y0079368*
X0275725Y0079215*
X0275612Y0079053*
X027551Y0078884*
X027542Y0078708*
X0275343Y0078527*
X0275279Y007834*
X0275228Y0078149*
X027519Y0077956*
X0275166Y007776*
X0275156Y0077563*
X0275156Y0077514*
X0273509Y0039234D02*
D01*
X0273713Y0039374*
X0273908Y0039529*
X0274091Y0039696*
X0274262Y0039876*
X027442Y0040068*
X0274564Y004027*
X0274694Y0040481*
X0274809Y0040702*
X0274908Y0040929*
X0274991Y0041163*
X0275057Y0041403*
X0275107Y0041646*
X0275139Y0041892*
X0275155Y004214*
X0275156Y0042235*
X026715Y0039936D02*
D01*
X026741Y0039692*
X0267687Y0039467*
X0267979Y0039263*
X0268284Y0039079*
X0268602Y0038916*
X026893Y0038777*
X0269267Y003866*
X0269611Y0038568*
X0269961Y0038499*
X0270315Y0038455*
X0270671Y0038436*
X0271027Y0038442*
X0271382Y0038473*
X0271735Y0038528*
X0272082Y0038608*
X0272423Y0038712*
X0272756Y0038839*
X027308Y003899*
X0273392Y0039162*
X0273509Y0039234*
X0274056Y0077514D02*
D01*
X0274049Y0077711*
X0274028Y0077907*
X0273994Y0078101*
X0273946Y0078293*
X0273885Y007848*
X0273811Y0078663*
X0273725Y0078841*
X0273626Y0079012*
X0273516Y0079175*
X0273394Y0079331*
X0273262Y0079477*
X0273228Y0079513*
X0270472Y0040551D02*
D01*
X0270576Y0040454*
X0270688Y0040365*
X0270805Y0040283*
X0270928Y004021*
X0271056Y0040146*
X0271188Y0040091*
X0271323Y0040046*
X0271461Y004001*
X0271601Y0039983*
X0271743Y0039967*
X0271886Y003996*
X0272029Y0039963*
X0272171Y0039977*
X0272312Y004*
X0272451Y0040033*
X0272587Y0040075*
X027272Y0040127*
X0272849Y0040188*
X0272973Y0040258*
X0273093Y0040337*
X0273206Y0040423*
X0273313Y0040518*
X0273406Y0040611*
X028937Y0079527D02*
D01*
X0289203Y0079348*
X0289049Y0079158*
X0288909Y0078958*
X0288783Y0078749*
X0288673Y0078531*
X0288577Y0078306*
X0288498Y0078075*
X0288434Y007784*
X0288388Y00776*
X0288358Y0077357*
X0288345Y0077114*
X0288345Y0077053*
X0288199Y0048202D02*
D01*
X0288198Y0048201*
X0288198Y0048201*
X0288197Y00482*
X0288197Y00482*
X0288197Y00482*
X0287245Y0077053D02*
D01*
X0287236Y0077297*
X028721Y0077539*
X0287168Y007778*
X0287109Y0078017*
X0287033Y0078249*
X0286942Y0078476*
X0286835Y0078695*
X0286713Y0078907*
X0286576Y0079109*
X0286426Y0079302*
X0286262Y0079483*
X0286221Y0079528*
X0287098Y0048909D02*
D01*
X0287121Y0048934*
X0287143Y0048961*
X0287163Y004899*
X0287181Y004902*
X0287197Y0049051*
X0287211Y0049083*
X0287222Y0049116*
X0287231Y0049149*
X0287238Y0049184*
X0287242Y0049218*
X0287244Y0049253*
X0287245Y0049263*
X0284925Y0040341D02*
D01*
X0284975Y0040342*
X0285025Y0040347*
X0285074Y0040356*
X0285123Y0040368*
X028517Y0040384*
X0285217Y0040403*
X0285262Y0040425*
X0285306Y004045*
X0285347Y0040478*
X0285387Y0040509*
X0285424Y0040542*
X0285433Y0040551*
X0284802Y0040341D02*
D01*
X028476Y0040339*
X0284719Y0040335*
X0284679Y0040328*
X0284639Y0040318*
X02846Y0040305*
X0284562Y0040289*
X0284525Y0040271*
X0284489Y0040251*
X0284455Y0040228*
X0284422Y0040202*
X0284392Y0040175*
X0284384Y0040168*
D01*
X0284355Y0040137*
X028433Y0040105*
X0284306Y0040072*
X0284285Y0040036*
X0284266Y004*
X028425Y0039962*
X0284237Y0039923*
X0284226Y0039883*
X0284218Y0039843*
X0284213Y0039802*
X0284211Y0039761*
X0284211Y0039751*
X0281193Y0043004D02*
D01*
X0281052Y0042851*
X0280922Y0042688*
X0280803Y0042518*
X0280697Y0042339*
X0280604Y0042153*
X0280524Y0041961*
X0280457Y0041765*
X0280405Y0041563*
X0280366Y0041359*
X0280342Y0041153*
X0280332Y0040945*
X0280337Y0040756*
Y0040752D02*
D01*
X0280351Y00406*
X0280376Y004045*
X0280412Y0040302*
X0280457Y0040157*
X0280513Y0040015*
X0280579Y0039878*
X0280654Y0039745*
X0280738Y0039619*
X028083Y0039498*
X0280931Y0039384*
X028097Y0039346*
X0280972Y0039343D02*
D01*
X0281086Y0039237*
X0281207Y0039141*
X0281335Y0039052*
X0281469Y0038973*
X0281608Y0038904*
X0281752Y0038844*
X0281899Y0038795*
X0282049Y0038756*
X0282202Y0038727*
X0282356Y003871*
X0282512Y0038703*
X0282667Y0038706*
X0282822Y0038721*
X0282975Y0038747*
X0283126Y0038783*
X0283274Y0038829*
X0283419Y0038886*
X0283559Y0038953*
X0283695Y0039029*
X0283824Y0039115*
X0283948Y0039209*
X0284051Y00393*
X0297931Y0040986D02*
D01*
X0297953Y0040971*
X0297976Y0040957*
X0297999Y0040943*
X0298022Y0040928*
X0298045Y0040914*
X0298046Y0040915*
X0282372Y0097318D02*
D01*
X0282287Y0097226*
X0282208Y009713*
X0282137Y0097028*
X0282073Y0096921*
X0282016Y009681*
X0281967Y0096695*
X0281927Y0096577*
X0281895Y0096457*
X0281871Y0096335*
X0281856Y0096211*
X0281849Y0096087*
X0281849Y0096056*
D01*
X0281853Y0095931*
X0281866Y0095807*
X0281888Y0095684*
X0281918Y0095563*
X0281956Y0095445*
X0282003Y0095329*
X0282057Y0095217*
X028212Y009511*
X0282189Y0095006*
X0282266Y0094908*
X0282349Y0094816*
X0282372Y0094793*
X029362Y0080876D02*
D01*
X0293604Y0081325*
X0293557Y0081772*
X0293479Y0082215*
X029337Y0082652*
X0293231Y0083079*
X0293062Y0083497*
X0292865Y0083901*
X029264Y008429*
X0292389Y0084663*
X0292112Y0085018*
X0291811Y0085352*
X0291732Y0085433*
X0298446Y0039102D02*
D01*
X0298822Y0039126*
X0299195Y0039177*
X0299565Y0039253*
X0299928Y0039355*
X0300283Y0039483*
X0300628Y0039634*
X0300962Y003981*
X0301282Y0040008*
X0301589Y0040228*
X0301879Y0040469*
X0301969Y0040551*
X0295348Y0039984D02*
D01*
X029535Y0039981*
X0295353Y0039978*
X0295355Y0039976*
X0295358Y0039973*
X0295361Y0039971*
X0295398Y0039935D02*
D01*
X0295407Y0039928*
X0295417Y0039922*
X0295426Y0039916*
X0295436Y003991*
X0295446Y0039905*
X0298446Y0039102D02*
D01*
X0298411Y0039099*
X0298376Y0039095*
X0298372Y0039094*
X0297481Y0039154D02*
D01*
X0297605Y0039118*
X0297731Y0039092*
X0297859Y0039075*
X0297988Y0039066*
X0298117Y0039067*
X0298246Y0039076*
X0298372Y0039094*
X029252Y0078948D02*
D01*
X0292495Y0079645*
X0292422Y0080339*
X0292301Y0081027*
X0292132Y0081704*
X0291916Y0082368*
X0291655Y0083015*
X0291349Y0083642*
X0291Y0084247*
X029061Y0084825*
X029018Y0085375*
X0289713Y0085894*
X0289591Y0086019*
X029252Y0047002D02*
D01*
X0292543Y0046299*
X0292615Y0045599*
X0292736Y0044907*
X0292905Y0044224*
X0293121Y0043555*
X0293383Y0042902*
X029369Y004227*
X029404Y004166*
X0294432Y0041077*
X0294864Y0040522*
X0295334Y0039998*
X0295348Y0039984*
X0280749Y0095828D02*
D01*
X0280754Y0095665*
X0280771Y0095503*
X02808Y0095342*
X0280839Y0095184*
X0280889Y0095029*
X028095Y0094878*
X0281022Y0094731*
X0281103Y009459*
X0281194Y0094455*
X0281295Y0094327*
X0281404Y0094205*
X0281433Y0094177*
X0280749Y0095828D02*
D01*
X0280743Y009599*
X0280726Y0096152*
X0280697Y0096313*
X0280658Y0096471*
X0280608Y0096626*
X0280547Y0096777*
X0280475Y0096924*
X0280394Y0097065*
X0280303Y00972*
X0280202Y0097328*
X0280093Y009745*
X0280065Y0097479*
X024252Y0043675D02*
D01*
X0242531Y004335*
X0242565Y0043027*
X0242621Y0042707*
X02427Y0042392*
X02428Y0042083*
X0242922Y0041782*
X0243064Y004149*
X0243227Y0041208*
X0243408Y0040939*
X0243608Y0040683*
X0243826Y0040442*
X0244059Y0040216*
X0244308Y0040007*
X0244571Y0039816*
X0244847Y0039644*
X0245133Y0039492*
X024543Y0039359*
X0245735Y0039248*
X0246048Y0039159*
X0246365Y0039091*
X0246687Y0039046*
X0247011Y0039023*
X0247173Y0039021*
X0295446Y0039905D02*
D01*
X0295773Y0039718*
X0296113Y0039554*
X0296463Y0039415*
X0296823Y00393*
X0297189Y0039211*
X029741Y0039171*
X0297481Y0039154D02*
D01*
X0297447Y0039163*
X0297413Y003917*
X029741Y0039171*
X0296674Y0044339D02*
D01*
X0296621Y0044337*
X0296569Y0044331*
X0296518Y0044322*
X0296467Y0044309*
X0296417Y0044293*
X0296368Y0044274*
X0296321Y0044251*
X0296276Y0044225*
X0296233Y0044195*
X0296191Y0044163*
X0296153Y0044128*
X0296116Y004409*
X0296082Y004405*
X0296052Y0044008*
X0296024Y0043964*
X0295999Y0043917*
X0295978Y0043869*
X029596Y004382*
X0295946Y004377*
X0295935Y0043719*
X0295928Y0043667*
X0295924Y0043615*
Y0043562*
X0295928Y004351*
X0295935Y0043458*
X0295946Y0043407*
X029596Y0043357*
X0295969Y0043334*
X0297563Y0041236D02*
D01*
X0297635Y0041184*
X0297708Y0041133*
X0297781Y0041083*
X0297856Y0041034*
X0297931Y0040986*
X0296674Y0044339D02*
D01*
X0296726Y004434*
X0296778Y0044346*
X0296829Y0044355*
X029688Y0044368*
X029693Y0044384*
X0296979Y0044403*
X0297026Y0044426*
X0297071Y0044452*
X0297114Y0044482*
X0297156Y0044514*
X0297194Y0044549*
X0297231Y0044587*
X0297265Y0044627*
X0297295Y0044669*
X0297323Y0044714*
X0297348Y004476*
X0297369Y0044808*
X0297387Y0044857*
X0297401Y0044907*
X0297412Y0044958*
X0297419Y004501*
X0297423Y0045062*
Y0045115*
X0297419Y0045167*
X0297412Y0045219*
X0297401Y004527*
X0297387Y004532*
X0297369Y0045369*
X0297348Y0045417*
X0297323Y0045464*
X0297295Y0045508*
X0297265Y004555*
X0297231Y004559*
X0297194Y0045628*
X0297156Y0045663*
X0297114Y0045695*
X0297071Y0045725*
X0297026Y0045751*
X0296979Y0045774*
X029693Y0045793*
X029688Y0045809*
X0296829Y0045822*
X0296778Y0045831*
X0296726Y0045837*
X0296674Y0045839*
X0294522Y0047339D02*
D01*
X0294469Y0047337*
X0294417Y0047331*
X0294366Y0047322*
X0294315Y0047309*
X0294265Y0047293*
X0294216Y0047274*
X0294169Y0047251*
X0294124Y0047225*
X0294081Y0047195*
X0294039Y0047163*
X0294001Y0047128*
X0293964Y004709*
X029393Y004705*
X02939Y0047008*
X0293872Y0046964*
X0293847Y0046917*
X0293826Y0046869*
X0293808Y004682*
X0293794Y004677*
X0293783Y0046719*
X0293776Y0046667*
X0293772Y0046615*
Y0046562*
X0293776Y004651*
X0293783Y0046458*
X0293794Y0046407*
X0293808Y0046357*
X0293826Y0046308*
X0293847Y004626*
X0293872Y0046214*
X02939Y0046169*
X029393Y0046127*
X0293964Y0046087*
X0294001Y0046049*
X0294039Y0046014*
X0294081Y0045982*
X0294124Y0045952*
X0294169Y0045926*
X0294216Y0045903*
X0294265Y0045884*
X0294315Y0045868*
X0294366Y0045855*
X0294417Y0045846*
X0294469Y004584*
X0294522Y0045839*
X0295512Y0047339D02*
D01*
X0295564Y004734*
X0295616Y0047346*
X0295667Y0047355*
X0295718Y0047368*
X0295768Y0047384*
X0295817Y0047403*
X0295864Y0047426*
X0295909Y0047452*
X0295952Y0047482*
X0295994Y0047514*
X0296032Y0047549*
X0296069Y0047587*
X0296103Y0047627*
X0296133Y0047669*
X0296161Y0047714*
X0296186Y004776*
X0296207Y0047808*
X0296225Y0047857*
X0296239Y0047907*
X029625Y0047958*
X0296257Y004801*
X0296261Y0048062*
Y0048115*
X0296257Y0048167*
X029625Y0048219*
X0296239Y004827*
X0296225Y004832*
X0296207Y0048369*
X0296186Y0048417*
X0296161Y0048464*
X0296133Y0048508*
X0296103Y004855*
X0296069Y004859*
X0296032Y0048628*
X0295994Y0048663*
X0295952Y0048695*
X0295909Y0048725*
X0295864Y0048751*
X0295817Y0048774*
X0295768Y0048793*
X0295718Y0048809*
X0295667Y0048822*
X0295616Y0048831*
X0295564Y0048837*
X0295512Y0048839*
X0293802Y0049334D02*
D01*
X0293821Y0049285*
X0293844Y0049238*
X029387Y0049192*
X0293899Y0049149*
X0293931Y0049108*
X0293966Y0049069*
X0294004Y0049032*
X0294044Y0048999*
X0294086Y0048968*
X029413Y004894*
X0294177Y0048915*
X0294224Y0048894*
X0294273Y0048876*
X0294324Y0048861*
X0294375Y004885*
X0294427Y0048843*
X0294479Y0048839*
X0294507Y0048839*
X028475Y0043692D02*
D01*
X0284711Y0043727*
X0284671Y004376*
X0284628Y004379*
X0284583Y0043817*
X0284536Y0043841*
X0284488Y0043861*
X0284439Y0043878*
X0284388Y0043892*
X0284337Y0043902*
X0284285Y0043908*
X0284233Y0043911*
X028418Y004391*
X0284128Y0043905*
X0284076Y0043897*
X0284026Y0043885*
X0283975Y004387*
X0283927Y0043851*
X0283879Y0043829*
X0283833Y0043804*
X028379Y0043775*
X0283748Y0043744*
X0283708Y004371*
X0283689Y0043692*
X0285152Y004329D02*
D01*
X028519Y0043254*
X028523Y0043221*
X0285273Y0043191*
X0285318Y0043164*
X0285365Y004314*
X0285413Y004312*
X0285462Y0043103*
X0285513Y0043089*
X0285564Y0043079*
X0285616Y0043073*
X0285668Y004307*
X0285721Y0043071*
X0285773Y0043076*
X0285825Y0043084*
X0285875Y0043096*
X0285926Y0043111*
X0285974Y004313*
X0286022Y0043152*
X0286068Y0043177*
X0286111Y0043206*
X0286153Y0043237*
X0286193Y0043271*
X0286213Y004329*
D01*
X0286248Y0043328*
X0286281Y0043368*
X0286311Y0043411*
X0286338Y0043456*
X0286362Y0043503*
X0286382Y0043551*
X0286399Y00436*
X0286413Y0043651*
X0286423Y0043702*
X0286429Y0043754*
X0286432Y0043806*
X0286431Y0043859*
X0286426Y0043911*
X0286418Y0043963*
X0286406Y0044013*
X0286391Y0044064*
X0286372Y0044112*
X028635Y004416*
X0286325Y0044206*
X0286296Y0044249*
X0286265Y0044291*
X0286231Y0044331*
X0286213Y0044351*
X0285614Y0046011D02*
D01*
X0285578Y0045972*
X0285545Y0045932*
X0285515Y0045889*
X0285488Y0045844*
X0285464Y0045797*
X0285444Y0045749*
X0285427Y00457*
X0285413Y0045649*
X0285403Y0045598*
X0285397Y0045546*
X0285394Y0045494*
X0285395Y0045441*
X02854Y0045389*
X0285408Y0045337*
X028542Y0045287*
X0285435Y0045236*
X0285454Y0045188*
X0285476Y004514*
X0285501Y0045094*
X028553Y0045051*
X0285561Y0045009*
X0285595Y0044969*
X0285614Y004495*
X0286674Y0046011D02*
D01*
X0286635Y0046046*
X0286595Y0046079*
X0286552Y0046109*
X0286507Y0046136*
X028646Y004616*
X0286412Y004618*
X0286363Y0046197*
X0286312Y0046211*
X0286261Y0046221*
X0286209Y0046227*
X0286157Y004623*
X0286104Y0046229*
X0286052Y0046224*
X0286Y0046216*
X028595Y0046204*
X0285899Y0046189*
X0285851Y004617*
X0285803Y0046148*
X0285757Y0046123*
X0285714Y0046094*
X0285672Y0046063*
X0285632Y0046029*
X0285614Y0046011*
X0287273Y0045412D02*
D01*
X0287311Y0045376*
X0287351Y0045343*
X0287394Y0045313*
X0287439Y0045286*
X0287486Y0045262*
X0287534Y0045242*
X0287583Y0045225*
X0287634Y0045211*
X0287685Y0045201*
X0287737Y0045195*
X0287789Y0045192*
X0287842Y0045193*
X0287894Y0045198*
X0287946Y0045206*
X0287996Y0045218*
X0288047Y0045233*
X0288095Y0045252*
X0288143Y0045274*
X0288189Y0045299*
X0288232Y0045328*
X0288274Y0045359*
X0288314Y0045393*
X0288334Y0045412*
D01*
X0288369Y004545*
X0288402Y004549*
X0288432Y0045533*
X0288459Y0045578*
X0288483Y0045625*
X0288503Y0045673*
X028852Y0045722*
X0288534Y0045773*
X0288544Y0045824*
X028855Y0045876*
X0288553Y0045928*
X0288552Y0045981*
X0288547Y0046033*
X0288539Y0046085*
X0288527Y0046135*
X0288512Y0046186*
X0288493Y0046234*
X0288471Y0046282*
X0288446Y0046328*
X0288417Y0046371*
X0288386Y0046413*
X0288352Y0046453*
X0288334Y0046472*
X0287932Y0047935D02*
D01*
X0287896Y0047896*
X0287863Y0047856*
X0287833Y0047813*
X0287806Y0047768*
X0287782Y0047721*
X0287762Y0047673*
X0287745Y0047624*
X0287731Y0047573*
X0287721Y0047522*
X0287715Y004747*
X0287712Y0047418*
X0287713Y0047365*
X0287718Y0047313*
X0287726Y0047261*
X0287738Y0047211*
X0287753Y004716*
X0287772Y0047112*
X0287794Y0047064*
X0287819Y0047018*
X0287848Y0046975*
X0287879Y0046933*
X0287913Y0046893*
X0287932Y0046874*
X0273406Y0040611D02*
D01*
X0273499Y0040718*
X0273536Y0040765*
X0273537Y0040767D02*
D01*
X027355Y0040785*
X0273564Y0040804*
X0273578Y0040823*
X0273591Y0040842*
X0273604Y0040861*
X0273605Y0040861*
X0274056Y0043595D02*
D01*
X0274054Y0043647*
X0274048Y0043699*
X0274039Y004375*
X0274026Y0043801*
X027401Y0043851*
X0273991Y00439*
X0273968Y0043947*
X0273942Y0043992*
X0273912Y0044035*
X027388Y0044077*
X0273845Y0044115*
X0273807Y0044152*
X0273767Y0044186*
X0273725Y0044216*
X0273681Y0044244*
X0273634Y0044269*
X0273586Y004429*
X0273537Y0044308*
X0273487Y0044322*
X0273436Y0044333*
X0273384Y004434*
X0273332Y0044344*
X0273306Y0044345*
Y0045845D02*
D01*
X0273253Y0045843*
X0273201Y0045837*
X027315Y0045828*
X0273099Y0045815*
X0273049Y0045799*
X0273Y004578*
X0272953Y0045757*
X0272908Y0045731*
X0272865Y0045701*
X0272823Y0045669*
X0272785Y0045634*
X0272748Y0045596*
X0272714Y0045556*
X0272684Y0045514*
X0272656Y004547*
X0272631Y0045423*
X027261Y0045375*
X0272592Y0045326*
X0272578Y0045276*
X0272567Y0045225*
X027256Y0045173*
X0272556Y0045121*
Y0045068*
X027256Y0045016*
X0272567Y0044964*
X0272578Y0044913*
X0272592Y0044863*
X027261Y0044814*
X0272631Y0044766*
X0272656Y004472*
X0272684Y0044675*
X0272714Y0044633*
X0272748Y0044593*
X0272785Y0044555*
X0272823Y004452*
X0272865Y0044488*
X0272908Y0044458*
X0272953Y0044432*
X0273Y0044409*
X0273049Y004439*
X0273099Y0044374*
X027315Y0044361*
X0273201Y0044352*
X0273253Y0044346*
X0273306Y0044345*
X0273406Y0045845D02*
D01*
X0273458Y0045846*
X027351Y0045852*
X0273561Y0045861*
X0273612Y0045874*
X0273662Y004589*
X0273711Y0045909*
X0273758Y0045932*
X0273803Y0045958*
X0273846Y0045988*
X0273888Y004602*
X0273926Y0046055*
X0273963Y0046093*
X0273997Y0046133*
X0274027Y0046175*
X0274055Y004622*
X027408Y0046266*
X0274101Y0046314*
X0274119Y0046363*
X0274133Y0046413*
X0274144Y0046464*
X0274151Y0046516*
X0274155Y0046568*
Y0046621*
X0274151Y0046673*
X0274144Y0046725*
X0274133Y0046776*
X0274119Y0046826*
X0274101Y0046875*
X027408Y0046923*
X0274055Y004697*
X0274027Y0047014*
X0273997Y0047056*
X0273963Y0047096*
X0273926Y0047134*
X0273888Y0047169*
X0273846Y0047201*
X0273803Y0047231*
X0273758Y0047257*
X0273711Y004728*
X0273662Y0047299*
X0273612Y0047315*
X0273561Y0047328*
X027351Y0047337*
X0273458Y0047343*
X0273406Y0047345*
X0273221Y0048845D02*
D01*
X0273168Y0048843*
X0273116Y0048837*
X0273065Y0048828*
X0273014Y0048815*
X0272964Y0048799*
X0272915Y004878*
X0272868Y0048757*
X0272823Y0048731*
X027278Y0048701*
X0272738Y0048669*
X02727Y0048634*
X0272663Y0048596*
X0272629Y0048556*
X0272599Y0048514*
X0272571Y004847*
X0272546Y0048423*
X0272525Y0048375*
X0272507Y0048326*
X0272493Y0048276*
X0272482Y0048225*
X0272475Y0048173*
X0272471Y0048121*
Y0048068*
X0272475Y0048016*
X0272482Y0047964*
X0272493Y0047913*
X0272507Y0047863*
X0272525Y0047814*
X0272546Y0047766*
X0272571Y004772*
X0272599Y0047675*
X0272629Y0047633*
X0272663Y0047593*
X02727Y0047555*
X0272738Y004752*
X027278Y0047488*
X0272823Y0047458*
X0272868Y0047432*
X0272915Y0047409*
X0272964Y004739*
X0273014Y0047374*
X0273065Y0047361*
X0273116Y0047352*
X0273168Y0047346*
X0273221Y0047345*
X0273406Y0048845D02*
D01*
X0273458Y0048846*
X027351Y0048852*
X0273561Y0048861*
X0273612Y0048874*
X0273662Y004889*
X0273711Y0048909*
X0273758Y0048932*
X0273803Y0048958*
X0273846Y0048988*
X0273888Y004902*
X0273926Y0049055*
X0273963Y0049093*
X0273997Y0049133*
X0274027Y0049175*
X0274055Y004922*
X027408Y0049266*
X0274101Y0049314*
X0274119Y0049363*
X0274133Y0049413*
X0274144Y0049464*
X0274151Y0049516*
X0274155Y0049568*
Y0049621*
X0274151Y0049673*
X0274144Y0049725*
X0274133Y0049776*
X0274119Y0049826*
X0274101Y0049875*
X027408Y0049923*
X0274055Y004997*
X0274027Y0050014*
X0273997Y0050056*
X0273963Y0050096*
X0273926Y0050134*
X0273888Y0050169*
X0273846Y0050201*
X0273803Y0050231*
X0273758Y0050257*
X0273711Y005028*
X0273662Y0050299*
X0273612Y0050315*
X0273561Y0050328*
X027351Y0050337*
X0273458Y0050343*
X0273406Y0050345*
X0273105Y0051845D02*
D01*
X0273052Y0051843*
X0273Y0051837*
X0272949Y0051828*
X0272898Y0051815*
X0272848Y0051799*
X0272799Y005178*
X0272752Y0051757*
X0272707Y0051731*
X0272664Y0051701*
X0272622Y0051669*
X0272584Y0051634*
X0272547Y0051596*
X0272513Y0051556*
X0272483Y0051514*
X0272455Y005147*
X027243Y0051423*
X0272409Y0051375*
X0272391Y0051326*
X0272377Y0051276*
X0272366Y0051225*
X0272359Y0051173*
X0272355Y0051121*
Y0051068*
X0272359Y0051016*
X0272366Y0050964*
X0272377Y0050913*
X0272391Y0050863*
X0272409Y0050814*
X027243Y0050766*
X0272455Y005072*
X0272483Y0050675*
X0272513Y0050633*
X0272547Y0050593*
X0272584Y0050555*
X0272622Y005052*
X0272664Y0050488*
X0272707Y0050458*
X0272752Y0050432*
X0272799Y0050409*
X0272848Y005039*
X0272898Y0050374*
X0272949Y0050361*
X0273Y0050352*
X0273052Y0050346*
X0273105Y0050345*
X0273306Y0051845D02*
D01*
X0273358Y0051846*
X027341Y0051852*
X0273461Y0051861*
X0273512Y0051874*
X0273562Y005189*
X0273611Y0051909*
X0273658Y0051932*
X0273703Y0051958*
X0273746Y0051988*
X0273788Y005202*
X0273826Y0052055*
X0273863Y0052093*
X0273897Y0052133*
X0273927Y0052175*
X0273955Y005222*
X027398Y0052266*
X0274001Y0052314*
X0274019Y0052363*
X0274033Y0052413*
X0274044Y0052464*
X0274051Y0052516*
X0274055Y0052568*
X0274056Y0052595*
X0240945Y0036623D02*
D01*
X0240994Y0036591*
X0241044Y0036559*
X0241094Y0036528*
X0241144Y0036498*
X0241195Y0036468*
X0241907Y0036273D02*
D01*
X0241957Y003626*
X0242009Y0036252*
X0242061Y0036247*
X0242113Y0036246*
X0242166Y0036248*
X0242218Y0036254*
X0242269Y0036264*
X024232Y0036277*
X0242369Y0036294*
X0242418Y0036314*
X0242464Y0036338*
X0242509Y0036365*
X0242552Y0036394*
X0242593Y0036427*
X0242632Y0036463*
X0242668Y0036501*
X0242701Y0036541*
X0242731Y0036584*
X0242758Y0036628*
X0242782Y0036675*
X0242803Y0036723*
X024282Y0036772*
X0242834Y0036823*
X0242844Y0036874*
X0242851Y0036926*
X0242854Y0036978*
X0242855Y0036997*
X0244355Y0037222D02*
D01*
X0244353Y0037274*
X0244347Y0037326*
X0244338Y0037377*
X0244325Y0037428*
X0244309Y0037478*
X024429Y0037527*
X0244267Y0037574*
X0244241Y0037619*
X0244211Y0037662*
X0244179Y0037704*
X0244144Y0037742*
X0244106Y0037779*
X0244066Y0037813*
X0244024Y0037843*
X024398Y0037871*
X0243933Y0037896*
X0243885Y0037917*
X0243836Y0037935*
X0243786Y0037949*
X0243735Y003796*
X0243683Y0037967*
X0243631Y0037971*
X0243578*
X0243526Y0037967*
X0243474Y003796*
X0243423Y0037949*
X0243373Y0037935*
X0243324Y0037917*
X0243276Y0037896*
X024323Y0037871*
X0243185Y0037843*
X0243143Y0037813*
X0243103Y0037779*
X0243065Y0037742*
X024303Y0037704*
X0242998Y0037662*
X0242968Y0037619*
X0242942Y0037574*
X0242919Y0037527*
X02429Y0037478*
X0242884Y0037428*
X0242871Y0037377*
X0242862Y0037326*
X0242856Y0037274*
X0242855Y0037222*
X0244355Y0036175D02*
D01*
X0244356Y0036122*
X0244362Y003607*
X0244371Y0036019*
X0244384Y0035968*
X02444Y0035918*
X0244419Y0035869*
X0244442Y0035822*
X0244468Y0035777*
X0244498Y0035734*
X024453Y0035692*
X0244565Y0035654*
X0244603Y0035617*
X0244643Y0035583*
X0244685Y0035553*
X024473Y0035525*
X0244776Y00355*
X0244824Y0035479*
X0244873Y0035461*
X0244907Y0035452*
X023973Y0037605D02*
D01*
X0240108Y0037251*
X024051Y0036926*
X0240934Y0036629*
X0240945Y0036623*
X0244488Y0050565D02*
D01*
X0244489Y0050512*
X0244495Y005046*
X0244504Y0050409*
X0244517Y0050358*
X0244533Y0050308*
X0244552Y0050259*
X0244575Y0050212*
X0244601Y0050167*
X0244631Y0050124*
X0244663Y0050082*
X0244698Y0050044*
X0244736Y0050007*
X0244776Y0049973*
X0244818Y0049943*
X0244863Y0049915*
X0244909Y004989*
X0244957Y0049869*
X0245006Y0049851*
X0245056Y0049837*
X0245107Y0049826*
X0245159Y0049819*
X0245211Y0049815*
X0245238Y0049815*
X0245672Y0048315D02*
D01*
X0245724Y0048316*
X0245776Y0048322*
X0245827Y0048331*
X0245878Y0048344*
X0245928Y004836*
X0245977Y0048379*
X0246024Y0048402*
X0246069Y0048428*
X0246112Y0048458*
X0246154Y004849*
X0246192Y0048525*
X0246229Y0048563*
X0246263Y0048603*
X0246293Y0048645*
X0246321Y004869*
X0246346Y0048736*
X0246367Y0048784*
X0246385Y0048833*
X0246399Y0048883*
X024641Y0048934*
X0246417Y0048986*
X0246421Y0049038*
Y0049091*
X0246417Y0049143*
X024641Y0049195*
X0246399Y0049246*
X0246385Y0049296*
X0246367Y0049345*
X0246346Y0049393*
X0246321Y004944*
X0246293Y0049484*
X0246263Y0049526*
X0246229Y0049566*
X0246192Y0049604*
X0246154Y0049639*
X0246112Y0049671*
X0246069Y0049701*
X0246024Y0049727*
X0245977Y004975*
X0245928Y0049769*
X0245878Y0049785*
X0245827Y0049798*
X0245776Y0049807*
X0245724Y0049813*
X0245672Y0049815*
X024427Y0048315D02*
D01*
X0244217Y0048313*
X0244165Y0048307*
X0244114Y0048298*
X0244063Y0048285*
X0244013Y0048269*
X0243964Y004825*
X0243917Y0048227*
X0243872Y0048201*
X0243829Y0048171*
X0243787Y0048139*
X0243749Y0048104*
X0243712Y0048066*
X0243678Y0048026*
X0243648Y0047984*
X024362Y004794*
X0243595Y0047893*
X0243574Y0047845*
X0243556Y0047796*
X0243542Y0047746*
X0243531Y0047695*
X0243524Y0047643*
X024352Y0047591*
Y0047538*
X0243524Y0047486*
X0243531Y0047434*
X0243542Y0047383*
X0243556Y0047333*
X0243574Y0047284*
X0243595Y0047236*
X024362Y004719*
X0243648Y0047145*
X0243678Y0047103*
X0243712Y0047063*
X0243749Y0047025*
X0243787Y004699*
X0243829Y0046958*
X0243872Y0046928*
X0243917Y0046902*
X0243964Y0046879*
X0244013Y004686*
X0244063Y0046844*
X0244114Y0046831*
X0244165Y0046822*
X0244217Y0046816*
X024427Y0046815*
X0245883Y0045315D02*
D01*
X0245935Y0045316*
X0245987Y0045322*
X0246038Y0045331*
X0246089Y0045344*
X0246139Y004536*
X0246188Y0045379*
X0246235Y0045402*
X024628Y0045428*
X0246323Y0045458*
X0246365Y004549*
X0246403Y0045525*
X024644Y0045563*
X0246474Y0045603*
X0246504Y0045645*
X0246532Y004569*
X0246557Y0045736*
X0246578Y0045784*
X0246596Y0045833*
X024661Y0045883*
X0246621Y0045934*
X0246628Y0045986*
X0246632Y0046038*
Y0046091*
X0246628Y0046143*
X0246621Y0046195*
X024661Y0046246*
X0246596Y0046296*
X0246578Y0046345*
X0246557Y0046393*
X0246532Y004644*
X0246504Y0046484*
X0246474Y0046526*
X024644Y0046566*
X0246403Y0046604*
X0246365Y0046639*
X0246323Y0046671*
X024628Y0046701*
X0246235Y0046727*
X0246188Y004675*
X0246139Y0046769*
X0246089Y0046785*
X0246038Y0046798*
X0245987Y0046807*
X0245935Y0046813*
X0245883Y0046815*
X0245238Y0045315D02*
D01*
X0245185Y0045313*
X0245133Y0045307*
X0245082Y0045298*
X0245031Y0045285*
X0244981Y0045269*
X0244932Y004525*
X0244885Y0045227*
X024484Y0045201*
X0244797Y0045171*
X0244755Y0045139*
X0244717Y0045104*
X024468Y0045066*
X0244646Y0045026*
X0244616Y0044984*
X0244588Y004494*
X0244563Y0044893*
X0244542Y0044845*
X0244524Y0044796*
X024451Y0044746*
X0244499Y0044695*
X0244492Y0044643*
X0244488Y0044591*
X0244488Y0044565*
X0288199Y0048202D02*
D01*
X0288222Y0048227*
X0288244Y0048254*
X0288264Y0048283*
X0288282Y0048313*
X0288298Y0048344*
X0288312Y0048376*
X0288323Y0048409*
X0288332Y0048442*
X0288339Y0048477*
X0288343Y0048511*
X0288345Y0048546*
X0288345Y0048555*
X0284051Y00393D02*
D01*
X0284075Y0039324*
X0284098Y003935*
X0284119Y0039378*
X0284138Y0039407*
X0284156Y0039438*
X028417Y003947*
X0284183Y0039502*
X0284193Y0039535*
X0284201Y0039569*
X0284207Y0039604*
X028421Y0039639*
X0284211Y0039667*
X0269354Y0094177D02*
D01*
X0269465Y0094296*
X0269567Y0094422*
X0269661Y0094556*
X0269745Y0094696*
X0269819Y0094841*
X0269882Y0094991*
X0269935Y0095145*
X0269978Y0095302*
X0270009Y0095462*
X0270028Y0095624*
X0270037Y0095787*
X0270038Y0095828*
X0259842Y0079513D02*
Y0079528D01*
X026067Y0046702D02*
Y0077514D01*
X0253543Y0035433D02*
X0257742Y0039631D01*
X0238058Y0040485D02*
X0238816D01*
X0237704Y0039631D02*
X023973Y0037605D01*
X0237558Y0039985D02*
D01*
X0262598Y0079513D02*
Y0079528D01*
Y0079513D02*
D01*
X0261771Y0046697D02*
Y0077514D01*
X0254318Y0034652D02*
X0258523Y0038857D01*
X0236458Y0039757D02*
Y0039985D01*
X02352Y0040485D02*
X0235958D01*
X0244959Y0034333D02*
X0253548D01*
X0270722Y0097479D02*
X0270866Y0097623D01*
X0246964Y004109D02*
X0246987Y0041098D01*
X0244488Y0056201D02*
Y0065168D01*
X0245315Y0041421D02*
X0245317Y0041419D01*
X024468Y0041962D02*
X0245312Y0041423D01*
X0244679Y0041963D02*
X024468Y0041962D01*
X026811Y0097623D02*
X0268415Y0097318D01*
X0268938Y0096056D02*
D01*
X0247638Y0074016D02*
X0268415Y0094793D01*
X0247828Y0039021D02*
X0249651D01*
X0246636Y0073013D02*
X0246639Y0073017D01*
X0275984Y0079513D02*
Y0079528D01*
Y0079513D02*
D01*
X0275156Y0042239D02*
Y0077514D01*
Y0042235D02*
Y0042239D01*
X026715Y0039936D02*
D01*
X0274056Y0054345D02*
Y0077514D01*
X0273228Y0079513D02*
Y0079528D01*
X0270472Y0040551D02*
D01*
X028937Y0079528D02*
Y0079527D01*
X0288345Y0050918D02*
Y0077053D01*
X0288109Y0048112D02*
X0288197Y00482D01*
X0287245Y0049263D02*
Y0077053D01*
X0287098Y0048909D02*
D01*
X0284802Y0040341D02*
X0284925D01*
X0281195Y0043006D02*
X0287098Y0048909D01*
X0281193Y0043004D02*
X0281195Y0043006D01*
X0280337Y0040756D02*
Y0040752D01*
X0284211Y0039667D02*
Y0039751D01*
X028097Y0039346D02*
X0280972Y0039343D01*
X0298046Y0040915D02*
D01*
X0282372Y0094793D02*
X0291732Y0085433D01*
X0282372Y0097318D02*
X0282677Y0097623D01*
X029362Y0049839D02*
Y0080876D01*
X0295361Y0039971D02*
X0295398Y0039935D01*
X0298446Y0039102D02*
D01*
X0298372Y0039094D02*
D01*
X0279921Y0097623D02*
X0280065Y0097479D01*
X029252Y0047002D02*
Y0078948D01*
X0295348Y0039984D02*
D01*
X0281433Y0094177D02*
X0289591Y0086019D01*
X0247824Y0039021D02*
X0247828D01*
X024252Y006308D02*
Y0043675D01*
X0247173Y0039021D02*
X0247824D01*
X0293802Y0049334D02*
D01*
X029629Y0042443D02*
X0297563Y0041236D01*
X0295969Y0043334D02*
X029629Y0042443D01*
X0295969Y0043334D02*
D01*
X0296674Y0044339D02*
D01*
X0294522Y0045839D02*
X0296674D01*
X0294522Y0047339D02*
X0295512D01*
X0294507Y0048839D02*
X0295512D01*
X029371Y0049589D02*
X0293802Y0049334D01*
X029362Y0049839D02*
X029371Y0049589D01*
X0281851Y0040652D02*
X0281975Y0040776D01*
X0281632Y0041212D02*
X0281664Y0041131D01*
X0281632Y0041212D02*
X0281744Y0041747D01*
X0283689Y0043692*
X028475D02*
X0285152Y004329D01*
X0285614Y004495D02*
X0286213Y0044351D01*
X0286674Y0046011D02*
X0287273Y0045412D01*
X0287932Y0046874D02*
X0288334Y0046472D01*
X0287932Y0047935D02*
D01*
X0288109Y0048112*
X0282178Y0040785D02*
X0282198D01*
X0282168Y0040776D02*
X0282178Y0040785D01*
X0281975Y0040776D02*
X0282168D01*
X0281664Y0041131D02*
X0281851Y0040652D01*
X0273536Y0040765D02*
X0273537Y0040767D01*
X0273605Y0040861D02*
X0274056Y0042319D01*
Y0043595*
X0273306Y0044345D02*
D01*
Y0045845D02*
X0273406D01*
X0273221Y0047345D02*
X0273406D01*
X0273221Y0048845D02*
X0273406D01*
X0273105Y0050345D02*
X0273406D01*
X0273105Y0051845D02*
X0273306D01*
X0274056Y0052595D02*
Y0054345D01*
X0241195Y0036468D02*
X0241907Y0036273D01*
D01*
X0242855Y0036997D02*
Y0037222D01*
X0244355Y0036175D02*
Y0037222D01*
X0244907Y0035452D02*
D01*
X0244974Y0035433*
X0246063*
X0246855*
X0253543*
X0244488Y0050565D02*
Y0056201D01*
X0245238Y0049815D02*
X0245672D01*
X024427Y0048315D02*
X0245672D01*
X024427Y0046815D02*
X0245883D01*
X0245238Y0045315D02*
X0245883D01*
X0244488Y0042815D02*
Y0044565D01*
Y0042376D02*
Y0042815D01*
X0248416Y0073238D02*
X0269354Y0094177D01*
X0246987Y0041098D02*
X0246988Y0041099D01*
X0288345Y0048555D02*
Y0050918D01*
X0266535Y0040551D02*
X026715Y0039936D01*
X0246639Y0073017D02*
X0247638Y0074016D01*
X0247417Y0072239D02*
X0248416Y0073238D01*
X0236765Y0039015D02*
X0238963Y0036816D01*
X0282677Y0097623D02*
Y0097638D01*
X0279921Y0097623D02*
Y0097638D01*
X026811Y0097623D02*
Y0097638D01*
X0270866Y0097623D02*
Y0097638D01*
G54D112*
X0241831Y0237303D02*
D01*
X0241254Y0237282*
X024068Y0237222*
X0240111Y0237122*
X0239552Y0236982*
X0239003Y0236804*
X0238468Y0236588*
X0237949Y0236335*
X0237449Y0236046*
X0236971Y0235723*
X0236516Y0235368*
X0236087Y0234982*
X0235686Y0234567*
X0235315Y0234125*
X0234976Y0233658*
X023467Y0233169*
X0234399Y0232659*
X0234165Y0232132*
X0233967Y0231589*
X0233808Y0231035*
X0233688Y023047*
X0233608Y0229899*
X0233568Y0229323*
X0233563Y0229035*
X0252953Y018741D02*
D01*
X0252977Y0186712*
X025305Y0186018*
X0253171Y018533*
X025334Y0184653*
X0253556Y0183989*
X0253817Y0183342*
X0254123Y0182715*
X0254472Y018211*
X0254862Y0181532*
X0255292Y0180982*
X0255759Y0180463*
X0255882Y0180339*
X0315083Y0121138D02*
D01*
X0315593Y0120661*
X0316135Y0120222*
X0316707Y0119822*
X0317305Y0119462*
X0317927Y0119146*
X031857Y0118873*
X031923Y0118646*
X0319904Y0118465*
X0320589Y0118332*
X0321282Y0118247*
X0321979Y011821*
X0322154Y0118209*
X0531443Y011528D02*
D01*
X0530932Y0115756*
X053039Y0116195*
X0529818Y0116595*
X052922Y0116955*
X0528598Y0117271*
X0527955Y0117544*
X0527295Y0117771*
X0526621Y0117952*
X0525936Y0118085*
X0525243Y011817*
X0524546Y0118207*
X0524372Y0118209*
X054873Y0237303D02*
D01*
X0549427Y0237327*
X0550121Y02374*
X0550809Y0237521*
X0551486Y023769*
X055215Y0237906*
X0552797Y0238167*
X0553424Y0238473*
X0554029Y0238822*
X0554607Y0239212*
X0555157Y0239642*
X0555676Y0240109*
X0556161Y0240611*
X055661Y0241146*
X055702Y0241711*
X055739Y0242303*
X0557717Y0242919*
X0558001Y0243556*
X055824Y0244212*
X0558432Y0244883*
X0558578Y0245566*
X0558675Y0246257*
X0558723Y0246954*
X055873Y0247303*
X0245178Y0187107D02*
D01*
X0245654Y0187617*
X0246093Y0188159*
X0246493Y0188731*
X0246853Y0189329*
X0247169Y0189951*
X0247442Y0190594*
X0247669Y0191254*
X024785Y0191928*
X0247983Y0192613*
X0248068Y0193306*
X0248105Y0194003*
X0248107Y0194178*
X0145366Y0091437D02*
D01*
X0146063Y0091461*
X0146757Y0091534*
X0147445Y0091655*
X0148122Y0091824*
X0148786Y009204*
X0149433Y0092301*
X015006Y0092607*
X0150665Y0092956*
X0151243Y0093346*
X0151793Y0093776*
X0152312Y0094243*
X0152437Y0094366*
X0192511Y0143504D02*
D01*
X0193208Y0143528*
X0193902Y0143601*
X019459Y0143722*
X0195267Y0143891*
X0195931Y0144107*
X0196578Y0144368*
X0197205Y0144674*
X019781Y0145023*
X0198388Y0145413*
X0198938Y0145843*
X0199457Y014631*
X0199583Y0146433*
X0242778Y0189629D02*
D01*
X0243254Y0190139*
X0243693Y0190681*
X0244093Y0191253*
X0244453Y0191851*
X0244769Y0192473*
X0245042Y0193116*
X0245269Y0193776*
X024545Y019445*
X0245583Y0195135*
X0245668Y0195828*
X0245705Y0196525*
X0245707Y01967*
X0228929Y0218898D02*
D01*
X0229626Y0218922*
X023032Y0218995*
X0231008Y0219116*
X0231685Y0219285*
X0232349Y0219501*
X0232996Y0219762*
X0233623Y0220068*
X0234228Y0220417*
X0234806Y0220807*
X0235356Y0221237*
X0235875Y0221704*
X0236Y0221827*
X0145973Y0218898D02*
D01*
X0145275Y0218873*
X0144581Y02188*
X0143893Y0218679*
X0143216Y021851*
X0142552Y0218294*
X0141905Y0218033*
X0141278Y0217727*
X0140673Y0217378*
X0140095Y0216988*
X0139545Y0216558*
X0139026Y0216091*
X0138902Y0215969*
X0239051Y0227437D02*
D01*
X0239089Y0227477*
X0239096Y0227485*
X0229035Y0220571D02*
D01*
X0229565Y0220589*
X0230093Y0220645*
X0230615Y0220737*
X023113Y0220865*
X0231635Y0221029*
X0232127Y0221228*
X0232604Y0221461*
X0233064Y0221726*
X0233504Y0222023*
X0233922Y0222349*
X0234317Y0222705*
X0234412Y0222798*
X0146677Y02235D02*
D01*
X0147187Y0223023*
X0147729Y0222584*
X0148301Y0222184*
X0148899Y0221824*
X0149521Y0221508*
X0150164Y0221235*
X0150824Y0221008*
X0151498Y0220827*
X0152183Y0220694*
X0152876Y0220609*
X0153573Y0220572*
X0153748Y0220571*
X0103347Y0227362D02*
X0107283Y0231299D01*
X004626Y0227362D02*
X0103347D01*
X0072835Y0117126D02*
X0112205D01*
X0068898Y0121063D02*
X0072835Y0117126D01*
X0045276Y0121063D02*
X0068898D01*
X0119587Y0091437D02*
X0145366D01*
X011939Y0143504D02*
X0192511D01*
X0249938Y0283527D02*
D01*
X0219488Y0313976D02*
X0249938Y0283527D01*
X0219488Y0313976D02*
Y0361221D01*
X0350362Y0303118D02*
X0350394D01*
X0343504Y029626D02*
X0350362Y0303118D01*
X0243142Y0267748D02*
X0266683Y0291289D01*
X0245079Y0265748D02*
X0267717Y0288386D01*
X024311Y0267748D02*
X0243142D01*
X0239173Y0265748D02*
X0245079D01*
X0237205Y0267717D02*
X0239173Y0265748D01*
X0267717Y0288386D02*
X029626D01*
X0301118Y0291276D02*
X030115Y0291307D01*
X029915Y0291276D02*
X0301118D01*
X029626Y0288386D02*
X029915Y0291276D01*
X0266683Y0291289D02*
X0294341D01*
X0251621Y0267048D02*
X0422194D01*
X0244882Y0260309D02*
X0251621Y0267048D01*
X0244882Y0260236D02*
Y0260309D01*
X0252953Y018741D02*
Y0229134D01*
X0248107Y0194178D02*
Y0229134D01*
X0231004Y0229035D02*
X0233563D01*
X021752Y0363189D02*
X0219488Y0361221D01*
X0314764Y027559D02*
X0343504D01*
X0312894Y0273721D02*
X0314764Y027559D01*
X0343504D02*
Y029626D01*
X030115Y0291307D02*
X0322835D01*
X0324803Y0293276*
X0296358Y0293307D02*
X0320866D01*
X0294341Y0291289D02*
X0296358Y0293307D01*
X0247638Y0260236D02*
X025315Y0265748D01*
X0411683D02*
X0418966Y0258465D01*
X0422194Y0267048D02*
X0430778Y0258465D01*
X025315Y0265748D02*
X0411683D01*
X0345472Y0262795D02*
X0346141Y0263464D01*
X0385158D02*
X0390158Y0258465D01*
X0346141Y0263464D02*
X0385158D01*
X0258858Y0262795D02*
X0345472D01*
X0390158Y0258465D02*
X0407156D01*
X0293307Y0201642D02*
Y021752D01*
Y0201642D02*
X0339121Y0155828D01*
X0289923Y0203187D02*
X0338583Y0154528D01*
X0289923Y0203187D02*
Y021752D01*
X0339121Y0155828D02*
X0372363D01*
X0338583Y0154528D02*
X0374016D01*
X0372363Y0155828D02*
X0377428Y0160893D01*
X0377275Y0157787D02*
X0386458D01*
X0374016Y0154528D02*
X0377275Y0157787D01*
X0377428Y0160893D02*
X0386433D01*
X0245707Y01967D02*
Y0228705D01*
X0245674Y0228738D02*
X0245707Y0228705D01*
X0236Y0221827D02*
X0243307Y0229134D01*
X0255882Y0180339D02*
X0315083Y0121138D01*
X0322154Y0118209D02*
X0524372D01*
X0531443Y011528D02*
X055873Y0087992D01*
X0241831Y0237303D02*
X054873D01*
X055873Y0247303D02*
Y0247835D01*
X0152437Y0094366D02*
X0245178Y0187107D01*
X0199583Y0146433D02*
X0242778Y0189629D01*
X0145973Y0218898D02*
X0228929D01*
X0119685Y0196752D02*
X0138902Y0215969D01*
X0239096Y0227485D02*
X0240613Y0229269D01*
X0234412Y0222798D02*
X0239051Y0227437D01*
X0153748Y0220571D02*
X0229035D01*
X011998Y0250197D02*
X0146677Y02235D01*
G54D113*
X0107283Y0177165D02*
Y0231299D01*
Y0122047D02*
Y0177165D01*
Y0122047D02*
X0112205Y0117126D01*
X0525591Y0300197D02*
X0529528Y0304134D01*
X0525591Y0298228D02*
Y0300197D01*
X0199803Y0363189D02*
X021752D01*
X0182087D02*
X0199803D01*
X0181794Y0362897D02*
X0182087Y0363189D01*
X0163992Y0362811D02*
X0181709D01*
X0181794Y0362897*
X0304134Y0339567D02*
Y0375D01*
X0109547Y0362811D02*
X0163992D01*
X0104667Y0357931D02*
X0109547Y0362811D01*
X0104667Y0357931D02*
X0107439Y0355159D01*
Y0353502D02*
Y0355159D01*
X0107283Y0353346D02*
X0107439Y0353502D01*
X0107283Y0231299D02*
Y0353346D01*
G54D120*
X0430778Y0258465D03*
X0418966D03*
X0407156D03*
X055873Y0247835D03*
Y0087992D03*
G54D126*
X0045276Y0121063D03*
X004626Y0227362D03*
X0107283Y0169291D03*
X0112205Y0117126D03*
X0338583Y0208661D03*
X0249938Y0283527D03*
X0350394Y0303118D03*
X024311Y0267748D03*
X0244882Y0260236D03*
X0252953Y0229134D03*
X0248107D03*
X0237205Y0267717D03*
X0525591Y0298228D03*
X05Y0295276D03*
X0595472Y0145669D03*
Y0141732D03*
X0597441Y0145669D03*
Y0141732D03*
X0595472Y0143701D03*
X0597441D03*
X0312894Y0273721D03*
X0343504Y027559D03*
X0304134Y0339567D03*
X0667108Y0314014D03*
Y0315982D03*
X0663171Y0314014D03*
Y0315982D03*
X066514D03*
Y0314014D03*
X0107283Y0177165D03*
Y0231299D03*
X021752Y0363189D03*
X0199803D03*
X0181794Y0362897D03*
X0163992Y0362811D03*
X0181102Y0409449D03*
X0173228D03*
X0064961Y0430118D03*
X0084646D03*
X0104331D03*
X0125D03*
X0320866Y0293307D03*
X030115Y0291307D03*
X0324803Y0293276D03*
X0294341Y0291289D03*
X0258858Y0262795D03*
X0247638Y0260236D03*
X0293307Y021752D03*
X0289923D03*
X0245674Y0228738D03*
X0373031Y0208661D03*
Y0206693D03*
Y0204724D03*
Y0202756D03*
X0338583Y0204724D03*
Y0202756D03*
Y0206693D03*
X0240613Y0229269D03*
X011998Y0250197D03*
X0119685Y0196752D03*
X011939Y0143504D03*
X0119587Y0091437D03*
X0243307Y0229134D03*
X0233563Y0229035D03*
X0231004D03*
X0386433Y0160893D03*
X0386458Y0157787D03*
X0270866Y0097638D03*
X0279921D03*
X0275984Y0079528D03*
X0262598D03*
X028937D03*
X0273228D03*
X0282677Y0097638D03*
X0259842Y0079528D03*
X026811Y0097638D03*
X0286221Y0079528D03*
X0251181Y0040551D03*
X0298046Y0040915D03*
X0282198Y0040785D03*
X0246988Y0041099D03*
X0285433Y0040551D03*
X0266535D03*
X0270472D03*
X0235039D03*
X0238976D03*
X0301969D03*
G54D130*
X0529528Y0304134D02*
X0653291D01*
X0508858D02*
X0529528D01*
X0653291D02*
X0663171Y0314014D01*
X05Y0295276D02*
X0508858Y0304134D01*
X0596457Y0146653D02*
X0597441Y0145669D01*
X0596457Y0146653D02*
Y016437D01*
X0558071Y0202756D02*
X0596457Y016437D01*
X0375984Y0202756D02*
X0558071D01*
M02*